(kicad_pcb
	(version 20260206)
	(generator "pcbnew")
	(generator_version "10.0")
	(general
		(thickness 1.6)
		(legacy_teardrops no)
	)
	(paper "A4")
	(title_block
		(title "03242023_DA0F0TMBIJ0_F0T_Motherboard_J_brd_V01_OCP.brd")
		(comment 1 "Grand Teton / footprint 3039 of 6105 (U2), pads 2477-2583 of 4677")
	)
	(layers
		(0 "F.Cu" signal "TOP")
		(4 "In1.Cu" signal "GND")
		(6 "In2.Cu" signal "IN1")
		(8 "In3.Cu" signal "GND1")
		(10 "In4.Cu" signal "IN2")
		(12 "In5.Cu" signal "GND2")
		(14 "In6.Cu" signal "IN3")
		(16 "In7.Cu" signal "GND3")
		(18 "In8.Cu" signal "VCC")
		(20 "In9.Cu" signal "VCC1")
		(22 "In10.Cu" signal "GND4")
		(24 "In11.Cu" signal "IN4")
		(26 "In12.Cu" signal "GND5")
		(28 "In13.Cu" signal "IN5")
		(30 "In14.Cu" signal "GND6")
		(32 "In15.Cu" signal "IN6")
		(34 "In16.Cu" signal "GND7")
		(2 "B.Cu" signal "BOTTOM")
		(9 "F.Adhes" user "F.Adhesive")
		(11 "B.Adhes" user "B.Adhesive")
		(13 "F.Paste" user "Package Geometry/Pastemask Top")
		(15 "B.Paste" user "Package Geometry/Pastemask Bottom")
		(5 "F.SilkS" user "Ref Des/Silkscreen Top")
		(7 "B.SilkS" user "Ref Des/Silkscreen Bottom")
		(1 "F.Mask" user "Board Geometry/Soldermask Top")
		(3 "B.Mask" user "Board Geometry/Soldermask Bottom")
		(17 "Dwgs.User" user "User.Drawings")
		(19 "Cmts.User" user "User.Comments")
		(21 "Eco1.User" user "User.Eco1")
		(23 "Eco2.User" user "User.Eco2")
		(25 "Edge.Cuts" user "Board Geometry/Outline")
		(27 "Margin" user)
		(31 "F.CrtYd" user "Package Geometry/Place Bound Top")
		(29 "B.CrtYd" user "Package Geometry/Place Bound Bottom")
		(35 "F.Fab" user "Ref Des/Assembly Top")
		(33 "B.Fab" user "Ref Des/Assembly Bottom")
	)
	(footprint ""
		(layer "F.Cu")
		(at 359.870248 -251.76988 90)
		(property "Reference" "U2"
			(at -74.416158 -44.488608 0)
			(unlocked yes)
			(layer "F.SilkS")
			(effects
				(font
					(size 1.6002 1.1938)
					(thickness 0.1524)
				)
				(justify left)
			)
		)
		(property "Value" ""
			(at 0 0 90)
			(layer "F.Fab")
			(effects
				(font
					(size 1.27 1.27)
				)
			)
		)
		(duplicate_pad_numbers_are_jumpers no)
		(pad "DB85" smd circle
			(at 32.541718 11.097514 270)
			(size 0.4318 0.4318)
			(layers "F.Cu" "F.Mask" "F.Paste")
			(net "P5E_CPU0_PE3_TX_DN<11>")
		)
		(pad "DB87" smd circle
			(at 34.169604 11.097514 270)
			(size 0.4318 0.4318)
			(layers "F.Cu" "F.Mask" "F.Paste")
			(net "GND")
		)
		(pad "DB89" smd circle
			(at 35.797236 11.097514 270)
			(size 0.4318 0.4318)
			(layers "F.Cu" "F.Mask" "F.Paste")
			(net "P5E_CPU0_PE3_RX_DN<12>")
		)
		(pad "DB91" smd oval
			(at 37.425122 11.097514)
			(size 0.381 0.4826)
			(drill
				(offset 0 -0.0508)
			)
			(layers "F.Cu" "F.Mask" "F.Paste")
			(net "GND")
		)
		(pad "DC1" smd oval
			(at -37.425122 11.457686 180)
			(size 0.381 0.4826)
			(drill
				(offset 0 -0.0508)
			)
			(layers "F.Cu" "F.Mask" "F.Paste")
			(net "GND")
		)
		(pad "DC3" smd circle
			(at -35.797236 11.457686 270)
			(size 0.4318 0.4318)
			(layers "F.Cu" "F.Mask" "F.Paste")
			(net "UPI_CPU1_CPU0_P0P1_DN<12>")
		)
		(pad "DC5" smd circle
			(at -34.169604 11.457686 270)
			(size 0.4318 0.4318)
			(layers "F.Cu" "F.Mask" "F.Paste")
			(net "GND")
		)
		(pad "DC7" smd circle
			(at -32.541718 11.457686 270)
			(size 0.4318 0.4318)
			(layers "F.Cu" "F.Mask" "F.Paste")
			(net "UPI_CPU0_CPU1_P1P0_DN<11>")
		)
		(pad "DC9" smd circle
			(at -30.914086 11.457686 270)
			(size 0.4318 0.4318)
			(layers "F.Cu" "F.Mask" "F.Paste")
			(net "GND")
		)
		(pad "DC11" smd circle
			(at -29.2862 11.457686 270)
			(size 0.4318 0.4318)
			(layers "F.Cu" "F.Mask" "F.Paste")
			(net "P5E_CPU0_PE2_RX_DP<3>")
		)
		(pad "DC13" smd circle
			(at -27.658314 11.457686 270)
			(size 0.4318 0.4318)
			(layers "F.Cu" "F.Mask" "F.Paste")
			(net "GND")
		)
		(pad "DC15" smd circle
			(at -26.030682 11.457686 270)
			(size 0.4318 0.4318)
			(layers "F.Cu" "F.Mask" "F.Paste")
			(net "P5E_CPU0_PE2_TX_DP<3>")
		)
		(pad "DC17" smd circle
			(at -24.402796 11.457686 270)
			(size 0.4318 0.4318)
			(layers "F.Cu" "F.Mask" "F.Paste")
			(net "M_H_CPU0_SB_DQ<31>")
		)
		(pad "DC19" smd circle
			(at -22.77491 11.457686 270)
			(size 0.4318 0.4318)
			(layers "F.Cu" "F.Mask" "F.Paste")
			(net "M_H_CPU0_SB_DQ<25>")
		)
		(pad "DC21" smd circle
			(at -21.147278 11.457686 270)
			(size 0.4318 0.4318)
			(layers "F.Cu" "F.Mask" "F.Paste")
			(net "GND")
		)
		(pad "DC23" smd circle
			(at -19.519392 11.457686 270)
			(size 0.4318 0.4318)
			(layers "F.Cu" "F.Mask" "F.Paste")
			(net "M_H_CPU0_SB_DQ<12>")
		)
		(pad "DC25" smd circle
			(at -17.89176 11.457686 270)
			(size 0.4318 0.4318)
			(layers "F.Cu" "F.Mask" "F.Paste")
			(net "M_H_CPU0_SB_DQ<9>")
		)
		(pad "DC27" smd circle
			(at -16.263874 11.457686 270)
			(size 0.4318 0.4318)
			(layers "F.Cu" "F.Mask" "F.Paste")
			(net "GND")
		)
		(pad "DC29" smd circle
			(at -14.635988 11.457686 270)
			(size 0.4318 0.4318)
			(layers "F.Cu" "F.Mask" "F.Paste")
			(net "M_H_CPU0_SB_DQ<4>")
		)
		(pad "DC31" smd circle
			(at -13.008356 11.457686 270)
			(size 0.4318 0.4318)
			(layers "F.Cu" "F.Mask" "F.Paste")
			(net "M_H_CPU0_SB_DQ<1>")
		)
		(pad "DC33" smd circle
			(at -11.380724 11.457686 270)
			(size 0.4318 0.4318)
			(layers "F.Cu" "F.Mask" "F.Paste")
			(net "GND")
		)
		(pad "DC35" smd circle
			(at -9.752838 11.457686 270)
			(size 0.4318 0.4318)
			(layers "F.Cu" "F.Mask" "F.Paste")
			(net "M_H_CPU0_SB_CB<0>")
		)
		(pad "DC37" smd circle
			(at -8.124952 11.457686 270)
			(size 0.4318 0.4318)
			(layers "F.Cu" "F.Mask" "F.Paste")
			(net "M_H_CPU0_SB_CB<7>")
		)
		(pad "DC39" smd circle
			(at -6.49732 11.457686 270)
			(size 0.4318 0.4318)
			(layers "F.Cu" "F.Mask" "F.Paste")
			(net "GND")
		)
		(pad "DC41" smd circle
			(at -4.869434 11.457686 270)
			(size 0.4318 0.4318)
			(layers "F.Cu" "F.Mask" "F.Paste")
			(net "M_H_CPU0_SA_CA<6>")
		)
		(pad "DC43" smd circle
			(at -3.241802 11.457686 270)
			(size 0.4318 0.4318)
			(layers "F.Cu" "F.Mask" "F.Paste")
			(net "M_E_CPU0_SA_RSP<1>")
		)
		(pad "DC45" smd circle
			(at -1.613916 11.457686 270)
			(size 0.4318 0.4318)
			(layers "F.Cu" "F.Mask" "F.Paste")
			(net "GND")
		)
		(pad "DC48" smd circle
			(at 2.427732 11.567668 270)
			(size 0.4318 0.4318)
			(layers "F.Cu" "F.Mask" "F.Paste")
			(net "M_H_CPU0_SA_CA<2>")
		)
		(pad "DC50" smd circle
			(at 4.055618 11.567668 270)
			(size 0.4318 0.4318)
			(layers "F.Cu" "F.Mask" "F.Paste")
			(net "M_H_CPU0_SA_CS_N<3>")
		)
		(pad "DC52" smd circle
			(at 5.68325 11.567668 270)
			(size 0.4318 0.4318)
			(layers "F.Cu" "F.Mask" "F.Paste")
			(net "GND")
		)
		(pad "DC54" smd circle
			(at 7.311136 11.567668 270)
			(size 0.4318 0.4318)
			(layers "F.Cu" "F.Mask" "F.Paste")
			(net "M_H_CPU0_SA_CB<4>")
		)
		(pad "DC56" smd circle
			(at 8.939022 11.567668 270)
			(size 0.4318 0.4318)
			(layers "F.Cu" "F.Mask" "F.Paste")
			(net "M_H_CPU0_SA_CB<1>")
		)
		(pad "DC58" smd circle
			(at 10.566654 11.567668 270)
			(size 0.4318 0.4318)
			(layers "F.Cu" "F.Mask" "F.Paste")
			(net "GND")
		)
		(pad "DC60" smd circle
			(at 12.19454 11.567668 270)
			(size 0.4318 0.4318)
			(layers "F.Cu" "F.Mask" "F.Paste")
			(net "M_H_CPU0_SA_DQ<28>")
		)
		(pad "DC62" smd circle
			(at 13.822426 11.567668 270)
			(size 0.4318 0.4318)
			(layers "F.Cu" "F.Mask" "F.Paste")
			(net "M_H_CPU0_SA_DQ<25>")
		)
		(pad "DC64" smd circle
			(at 15.450058 11.567668 270)
			(size 0.4318 0.4318)
			(layers "F.Cu" "F.Mask" "F.Paste")
			(net "GND")
		)
		(pad "DC66" smd circle
			(at 17.07769 11.567668 270)
			(size 0.4318 0.4318)
			(layers "F.Cu" "F.Mask" "F.Paste")
			(net "M_H_CPU0_SA_DQ<20>")
		)
		(pad "DC68" smd circle
			(at 18.705576 11.567668 270)
			(size 0.4318 0.4318)
			(layers "F.Cu" "F.Mask" "F.Paste")
			(net "M_H_CPU0_SA_DQ<17>")
		)
		(pad "DC70" smd circle
			(at 20.333462 11.567668 270)
			(size 0.4318 0.4318)
			(layers "F.Cu" "F.Mask" "F.Paste")
			(net "GND")
		)
		(pad "DC72" smd circle
			(at 21.961094 11.567668 270)
			(size 0.4318 0.4318)
			(layers "F.Cu" "F.Mask" "F.Paste")
			(net "M_H_CPU0_SA_DQ<12>")
		)
		(pad "DC74" smd circle
			(at 23.58898 11.567668 270)
			(size 0.4318 0.4318)
			(layers "F.Cu" "F.Mask" "F.Paste")
			(net "M_H_CPU0_SA_DQ<9>")
		)
		(pad "DC76" smd circle
			(at 25.216612 11.567668 270)
			(size 0.4318 0.4318)
			(layers "F.Cu" "F.Mask" "F.Paste")
			(net "GND")
		)
		(pad "DC78" smd circle
			(at 26.844498 11.567668 270)
			(size 0.4318 0.4318)
			(layers "F.Cu" "F.Mask" "F.Paste")
			(net "GND")
		)
		(pad "DC80" smd circle
			(at 28.472384 11.567668 270)
			(size 0.4318 0.4318)
			(layers "F.Cu" "F.Mask" "F.Paste")
			(net "GND")
		)
		(pad "DC82" smd circle
			(at 30.100016 11.567668 270)
			(size 0.4318 0.4318)
			(layers "F.Cu" "F.Mask" "F.Paste")
			(net "GND")
		)
		(pad "DC84" smd circle
			(at 31.727902 11.567668 270)
			(size 0.4318 0.4318)
			(layers "F.Cu" "F.Mask" "F.Paste")
			(net "GND")
		)
		(pad "DC86" smd circle
			(at 33.355534 11.567668 270)
			(size 0.4318 0.4318)
			(layers "F.Cu" "F.Mask" "F.Paste")
			(net "P5E_CPU0_PE3_TX_DP<11>")
		)
		(pad "DC88" smd circle
			(at 34.98342 11.567668 270)
			(size 0.4318 0.4318)
			(layers "F.Cu" "F.Mask" "F.Paste")
			(net "GND")
		)
		(pad "DC90" smd circle
			(at 36.611306 11.567668 270)
			(size 0.4318 0.4318)
			(layers "F.Cu" "F.Mask" "F.Paste")
			(net "P5E_CPU0_PE3_RX_DP<12>")
		)
		(pad "DD2" smd circle
			(at -36.611306 11.927332 270)
			(size 0.4318 0.4318)
			(layers "F.Cu" "F.Mask" "F.Paste")
			(net "UPI_CPU1_CPU0_P0P1_DP<12>")
		)
		(pad "DD4" smd circle
			(at -34.98342 11.927332 270)
			(size 0.4318 0.4318)
			(layers "F.Cu" "F.Mask" "F.Paste")
			(net "GND")
		)
		(pad "DD6" smd circle
			(at -33.355534 11.927332 270)
			(size 0.4318 0.4318)
			(layers "F.Cu" "F.Mask" "F.Paste")
			(net "UPI_CPU0_CPU1_P1P0_DP<11>")
		)
		(pad "DD8" smd circle
			(at -31.727902 11.927332 270)
			(size 0.4318 0.4318)
			(layers "F.Cu" "F.Mask" "F.Paste")
			(net "GND")
		)
		(pad "DD10" smd circle
			(at -30.100016 11.927332 270)
			(size 0.4318 0.4318)
			(layers "F.Cu" "F.Mask" "F.Paste")
			(net "P5E_CPU0_PE2_RX_DN<3>")
		)
		(pad "DD12" smd circle
			(at -28.472384 11.927332 270)
			(size 0.4318 0.4318)
			(layers "F.Cu" "F.Mask" "F.Paste")
			(net "GND")
		)
		(pad "DD14" smd circle
			(at -26.844498 11.927332 270)
			(size 0.4318 0.4318)
			(layers "F.Cu" "F.Mask" "F.Paste")
			(net "P5E_CPU0_PE2_TX_DP<4>")
		)
		(pad "DD16" smd circle
			(at -25.216612 11.927332 270)
			(size 0.4318 0.4318)
			(layers "F.Cu" "F.Mask" "F.Paste")
			(net "GND")
		)
		(pad "DD18" smd circle
			(at -23.58898 11.927332 270)
			(size 0.4318 0.4318)
			(layers "F.Cu" "F.Mask" "F.Paste")
			(net "M_H_CPU0_SB_DQS_DP<3>")
		)
		(pad "DD20" smd circle
			(at -21.961094 11.927332 270)
			(size 0.4318 0.4318)
			(layers "F.Cu" "F.Mask" "F.Paste")
			(net "M_H_CPU0_SB_DQ<24>")
		)
		(pad "DD22" smd circle
			(at -20.333462 11.927332 270)
			(size 0.4318 0.4318)
			(layers "F.Cu" "F.Mask" "F.Paste")
			(net "M_H_CPU0_SB_DQ<13>")
		)
		(pad "DD24" smd circle
			(at -18.705576 11.927332 270)
			(size 0.4318 0.4318)
			(layers "F.Cu" "F.Mask" "F.Paste")
			(net "M_H_CPU0_SB_DQS_DN<1>")
		)
		(pad "DD26" smd circle
			(at -17.07769 11.927332 270)
			(size 0.4318 0.4318)
			(layers "F.Cu" "F.Mask" "F.Paste")
			(net "M_H_CPU0_SB_DQ<8>")
		)
		(pad "DD28" smd circle
			(at -15.450058 11.927332 270)
			(size 0.4318 0.4318)
			(layers "F.Cu" "F.Mask" "F.Paste")
			(net "M_H_CPU0_SB_DQ<7>")
		)
		(pad "DD30" smd circle
			(at -13.822426 11.927332 270)
			(size 0.4318 0.4318)
			(layers "F.Cu" "F.Mask" "F.Paste")
			(net "M_H_CPU0_SB_DQS_DN<0>")
		)
		(pad "DD32" smd circle
			(at -12.19454 11.927332 270)
			(size 0.4318 0.4318)
			(layers "F.Cu" "F.Mask" "F.Paste")
			(net "M_H_CPU0_SB_DQ<0>")
		)
		(pad "DD34" smd circle
			(at -10.566654 11.927332 270)
			(size 0.4318 0.4318)
			(layers "F.Cu" "F.Mask" "F.Paste")
			(net "M_H_CPU0_SB_CB<1>")
		)
		(pad "DD36" smd circle
			(at -8.939022 11.927332 270)
			(size 0.4318 0.4318)
			(layers "F.Cu" "F.Mask" "F.Paste")
			(net "M_H_CPU0_SB_DQS_DN<9>")
		)
		(pad "DD38" smd circle
			(at -7.311136 11.927332 270)
			(size 0.4318 0.4318)
			(layers "F.Cu" "F.Mask" "F.Paste")
			(net "M_H_CPU0_SB_CB<6>")
		)
		(pad "DD40" smd circle
			(at -5.68325 11.927332 270)
			(size 0.4318 0.4318)
			(layers "F.Cu" "F.Mask" "F.Paste")
			(net "M_H_CPU0_SA_PAR")
		)
		(pad "DD42" smd circle
			(at -4.055618 11.927332 270)
			(size 0.4318 0.4318)
			(layers "F.Cu" "F.Mask" "F.Paste")
			(net "M_H_CPU0_CLK_DN<1>")
		)
		(pad "DD44" smd circle
			(at -2.427732 11.927332 270)
			(size 0.4318 0.4318)
			(layers "F.Cu" "F.Mask" "F.Paste")
			(net "M_E_CPU0_SA_RSP<0>")
		)
		(pad "DD47" smd circle
			(at 1.613916 12.037314 270)
			(size 0.4318 0.4318)
			(layers "F.Cu" "F.Mask" "F.Paste")
			(net "M_H_CPU0_SA_CA<4>")
		)
		(pad "DD49" smd circle
			(at 3.241802 12.037314 270)
			(size 0.4318 0.4318)
			(layers "F.Cu" "F.Mask" "F.Paste")
			(net "GND")
		)
		(pad "DD51" smd circle
			(at 4.869434 12.037314 270)
			(size 0.4318 0.4318)
			(layers "F.Cu" "F.Mask" "F.Paste")
			(net "M_H_CPU0_SA_CS_N<2>")
		)
		(pad "DD53" smd circle
			(at 6.49732 12.037314 270)
			(size 0.4318 0.4318)
			(layers "F.Cu" "F.Mask" "F.Paste")
			(net "M_H_CPU0_SA_CB<5>")
		)
		(pad "DD55" smd circle
			(at 8.124952 12.037314 270)
			(size 0.4318 0.4318)
			(layers "F.Cu" "F.Mask" "F.Paste")
			(net "M_H_CPU0_SA_DQS_DN<4>")
		)
		(pad "DD57" smd circle
			(at 9.752838 12.037314 270)
			(size 0.4318 0.4318)
			(layers "F.Cu" "F.Mask" "F.Paste")
			(net "M_H_CPU0_SA_CB<0>")
		)
		(pad "DD59" smd circle
			(at 11.380724 12.037314 270)
			(size 0.4318 0.4318)
			(layers "F.Cu" "F.Mask" "F.Paste")
			(net "M_H_CPU0_SA_DQ<29>")
		)
		(pad "DD61" smd circle
			(at 13.008356 12.037314 270)
			(size 0.4318 0.4318)
			(layers "F.Cu" "F.Mask" "F.Paste")
			(net "M_H_CPU0_SA_DQS_DN<3>")
		)
		(pad "DD63" smd circle
			(at 14.635988 12.037314 270)
			(size 0.4318 0.4318)
			(layers "F.Cu" "F.Mask" "F.Paste")
			(net "M_H_CPU0_SA_DQ<24>")
		)
		(pad "DD65" smd circle
			(at 16.263874 12.037314 270)
			(size 0.4318 0.4318)
			(layers "F.Cu" "F.Mask" "F.Paste")
			(net "M_H_CPU0_SA_DQ<21>")
		)
		(pad "DD67" smd circle
			(at 17.89176 12.037314 270)
			(size 0.4318 0.4318)
			(layers "F.Cu" "F.Mask" "F.Paste")
			(net "M_H_CPU0_SA_DQS_DN<2>")
		)
		(pad "DD69" smd circle
			(at 19.519392 12.037314 270)
			(size 0.4318 0.4318)
			(layers "F.Cu" "F.Mask" "F.Paste")
			(net "M_H_CPU0_SA_DQ<16>")
		)
		(pad "DD71" smd circle
			(at 21.147278 12.037314 270)
			(size 0.4318 0.4318)
			(layers "F.Cu" "F.Mask" "F.Paste")
			(net "M_H_CPU0_SA_DQ<13>")
		)
		(pad "DD73" smd circle
			(at 22.77491 12.037314 270)
			(size 0.4318 0.4318)
			(layers "F.Cu" "F.Mask" "F.Paste")
			(net "M_H_CPU0_SA_DQS_DP<1>")
		)
		(pad "DD75" smd circle
			(at 24.402796 12.037314 270)
			(size 0.4318 0.4318)
			(layers "F.Cu" "F.Mask" "F.Paste")
			(net "M_H_CPU0_SA_DQ<8>")
		)
		(pad "DD77" smd circle
			(at 26.030682 12.037314 270)
			(size 0.4318 0.4318)
			(layers "F.Cu" "F.Mask" "F.Paste")
			(net "PVCCFA_EHV_FIVRA_CPU0")
		)
		(pad "DD79" smd circle
			(at 27.658314 12.037314 270)
			(size 0.4318 0.4318)
			(layers "F.Cu" "F.Mask" "F.Paste")
			(net "GND")
		)
		(pad "DD81" smd circle
			(at 29.2862 12.037314 270)
			(size 0.4318 0.4318)
			(layers "F.Cu" "F.Mask" "F.Paste")
			(net "GND")
		)
		(pad "DD83" smd circle
			(at 30.914086 12.037314 270)
			(size 0.4318 0.4318)
			(layers "F.Cu" "F.Mask" "F.Paste")
			(net "PVCCFA_EHV_FIVRA_CPU0")
		)
		(pad "DD85" smd circle
			(at 32.541718 12.037314 270)
			(size 0.4318 0.4318)
			(layers "F.Cu" "F.Mask" "F.Paste")
			(net "PVCCFA_EHV_FIVRA_CPU0")
		)
		(pad "DD87" smd circle
			(at 34.169604 12.037314 270)
			(size 0.4318 0.4318)
			(layers "F.Cu" "F.Mask" "F.Paste")
			(net "P5E_CPU0_PE3_TX_DN<10>")
		)
		(pad "DD89" smd circle
			(at 35.797236 12.037314 270)
			(size 0.4318 0.4318)
			(layers "F.Cu" "F.Mask" "F.Paste")
			(net "PVCCFA_EHV_FIVRA_CPU0")
		)
		(pad "DD91" smd oval
			(at 37.425122 12.037314)
			(size 0.381 0.4826)
			(drill
				(offset 0 -0.0508)
			)
			(layers "F.Cu" "F.Mask" "F.Paste")
			(net "P5E_CPU0_PE3_RX_DN<11>")
		)
		(pad "DE1" smd oval
			(at -37.425122 12.397486 180)
			(size 0.381 0.4826)
			(drill
				(offset 0 -0.0508)
			)
			(layers "F.Cu" "F.Mask" "F.Paste")
			(net "UPI_CPU1_CPU0_P0P1_DN<11>")
		)
		(pad "DE3" smd circle
			(at -35.797236 12.397486 270)
			(size 0.4318 0.4318)
			(layers "F.Cu" "F.Mask" "F.Paste")
			(net "PVCCINFAON_CPU0")
		)
		(pad "DE5" smd circle
			(at -34.169604 12.397486 270)
			(size 0.4318 0.4318)
			(layers "F.Cu" "F.Mask" "F.Paste")
			(net "UPI_CPU0_CPU1_P1P0_DP<10>")
		)
		(pad "DE7" smd circle
			(at -32.541718 12.397486 270)
			(size 0.4318 0.4318)
			(layers "F.Cu" "F.Mask" "F.Paste")
			(net "PVCCINFAON_CPU0")
		)
		(pad "DE9" smd circle
			(at -30.914086 12.397486 270)
			(size 0.4318 0.4318)
			(layers "F.Cu" "F.Mask" "F.Paste")
			(net "P5E_CPU0_PE2_RX_DN<4>")
		)
		(pad "DE11" smd circle
			(at -29.2862 12.397486 270)
			(size 0.4318 0.4318)
			(layers "F.Cu" "F.Mask" "F.Paste")
			(net "PVCCINFAON_CPU0")
		)
		(pad "DE13" smd circle
			(at -27.658314 12.397486 270)
			(size 0.4318 0.4318)
			(layers "F.Cu" "F.Mask" "F.Paste")
			(net "P5E_CPU0_PE2_TX_DN<4>")
		)
		(pad "DE15" smd circle
			(at -26.030682 12.397486 270)
			(size 0.4318 0.4318)
			(layers "F.Cu" "F.Mask" "F.Paste")
			(net "PVCCINFAON_CPU0")
		)
		(pad "DE17" smd circle
			(at -24.402796 12.397486 270)
			(size 0.4318 0.4318)
			(layers "F.Cu" "F.Mask" "F.Paste")
			(net "GND")
		)
		(pad "DE19" smd circle
			(at -22.77491 12.397486 270)
			(size 0.4318 0.4318)
			(layers "F.Cu" "F.Mask" "F.Paste")
			(net "GND")
		)
		(pad "DE21" smd circle
			(at -21.147278 12.397486 270)
			(size 0.4318 0.4318)
			(layers "F.Cu" "F.Mask" "F.Paste")
			(net "GND")
		)
		(pad "DE23" smd circle
			(at -19.519392 12.397486 270)
			(size 0.4318 0.4318)
			(layers "F.Cu" "F.Mask" "F.Paste")
			(net "GND")
		)
		(pad "DE25" smd circle
			(at -17.89176 12.397486 270)
			(size 0.4318 0.4318)
			(layers "F.Cu" "F.Mask" "F.Paste")
			(net "GND")
		)
	)
)
